# S9S_MB_2U (Grand Teton) — schematic netlist excerpt (pin names and nets, part order shuffled) for the footprints in the layout excerpt that follows; sources: Cadence DE-HDL packaged netlist, KiCad conversion of 03242023_DA0F0TMBIJ0_F0T_Motherboard_J_brd_V01_OCP.brd

R4760  Q_RES  33.2 1% CHIP  pkg 0402LF  page 216 : A = HP_LVC3_OCP_V3_2_PWRGD_R ; B = HP_LVC3_OCP_V3_2_FUSE_PWRGD
PC1366  Q_CAP  0.1UF 25V 10% X7R  pkg 0402  page 294 : A = GND ; B = PVCCINFAON_CPU1_VREF

(kicad_pcb
	(version 20260206)
	(generator "pcbnew")
	(generator_version "10.0")
	(general
		(thickness 1.6)
		(legacy_teardrops no)
	)
	(paper "A4")
	(title_block
		(title "03242023_DA0F0TMBIJ0_F0T_Motherboard_J_brd_V01_OCP.brd")
		(comment 1 "Grand Teton / footprints 3410-3411 of 6105")
	)
	(layers
		(0 "F.Cu" signal "TOP")
		(4 "In1.Cu" signal "GND")
		(6 "In2.Cu" signal "IN1")
		(8 "In3.Cu" signal "GND1")
		(10 "In4.Cu" signal "IN2")
		(12 "In5.Cu" signal "GND2")
		(14 "In6.Cu" signal "IN3")
		(16 "In7.Cu" signal "GND3")
		(18 "In8.Cu" signal "VCC")
		(20 "In9.Cu" signal "VCC1")
		(22 "In10.Cu" signal "GND4")
		(24 "In11.Cu" signal "IN4")
		(26 "In12.Cu" signal "GND5")
		(28 "In13.Cu" signal "IN5")
		(30 "In14.Cu" signal "GND6")
		(32 "In15.Cu" signal "IN6")
		(34 "In16.Cu" signal "GND7")
		(2 "B.Cu" signal "BOTTOM")
		(9 "F.Adhes" user "F.Adhesive")
		(11 "B.Adhes" user "B.Adhesive")
		(13 "F.Paste" user "Package Geometry/Pastemask Top")
		(15 "B.Paste" user "Package Geometry/Pastemask Bottom")
		(5 "F.SilkS" user "Ref Des/Silkscreen Top")
		(7 "B.SilkS" user "Ref Des/Silkscreen Bottom")
		(1 "F.Mask" user "Board Geometry/Soldermask Top")
		(3 "B.Mask" user "Board Geometry/Soldermask Bottom")
		(17 "Dwgs.User" user "User.Drawings")
		(19 "Cmts.User" user "User.Comments")
		(21 "Eco1.User" user "User.Eco1")
		(23 "Eco2.User" user "User.Eco2")
		(25 "Edge.Cuts" user "Board Geometry/Outline")
		(27 "Margin" user)
		(31 "F.CrtYd" user "Package Geometry/Place Bound Top")
		(29 "B.CrtYd" user "Package Geometry/Place Bound Bottom")
		(35 "F.Fab" user "Ref Des/Assembly Top")
		(33 "B.Fab" user "Ref Des/Assembly Bottom")
	)
	(footprint ""
		(layer "F.Cu")
		(at 49.161954 -173.047914)
		(property "Reference" "PC1366"
			(at 0 0 0)
			(layer "F.SilkS")
			(hide yes)
			(effects
				(font
					(size 1.27 1.27)
				)
			)
		)
		(property "Value" ""
			(at 0 0 0)
			(layer "F.Fab")
			(effects
				(font
					(size 1.27 1.27)
				)
			)
		)
		(duplicate_pad_numbers_are_jumpers no)
		(fp_line
			(start -0.7874 -0.4064)
			(end 0.7874 -0.4064)
			(stroke
				(width 0.1524)
				(type default)
			)
			(layer "F.SilkS")
		)
		(fp_line
			(start -0.7874 0.4064)
			(end -0.7874 -0.4064)
			(stroke
				(width 0.1524)
				(type default)
			)
			(layer "F.SilkS")
		)
		(fp_line
			(start 0.7874 -0.4064)
			(end 0.7874 0.4064)
			(stroke
				(width 0.1524)
				(type default)
			)
			(layer "F.SilkS")
		)
		(fp_line
			(start 0.7874 0.4064)
			(end -0.7874 0.4064)
			(stroke
				(width 0.1524)
				(type default)
			)
			(layer "F.SilkS")
		)
		(fp_line
			(start -0.67945 -0.305054)
			(end -0.12065 -0.305054)
			(stroke
				(width 0.1)
				(type default)
			)
			(layer "F.Fab")
		)
		(fp_line
			(start -0.67945 0.3048)
			(end -0.67945 -0.305054)
			(stroke
				(width 0.1)
				(type default)
			)
			(layer "F.Fab")
		)
		(fp_line
			(start -0.12065 -0.305054)
			(end -0.12065 -0.2794)
			(stroke
				(width 0.1)
				(type default)
			)
			(layer "F.Fab")
		)
		(fp_line
			(start -0.12065 -0.2794)
			(end 0.12065 -0.2794)
			(stroke
				(width 0.1)
				(type default)
			)
			(layer "F.Fab")
		)
		(fp_line
			(start -0.12065 0.2794)
			(end -0.12065 0.3048)
			(stroke
				(width 0.1)
				(type default)
			)
			(layer "F.Fab")
		)
		(fp_line
			(start -0.12065 0.3048)
			(end -0.67945 0.3048)
			(stroke
				(width 0.1)
				(type default)
			)
			(layer "F.Fab")
		)
		(fp_line
			(start 0.120396 0.2794)
			(end -0.12065 0.2794)
			(stroke
				(width 0.1)
				(type default)
			)
			(layer "F.Fab")
		)
		(fp_line
			(start 0.120396 0.3048)
			(end 0.120396 0.2794)
			(stroke
				(width 0.1)
				(type default)
			)
			(layer "F.Fab")
		)
		(fp_line
			(start 0.12065 -0.3048)
			(end 0.67945 -0.3048)
			(stroke
				(width 0.1)
				(type default)
			)
			(layer "F.Fab")
		)
		(fp_line
			(start 0.12065 -0.2794)
			(end 0.12065 -0.3048)
			(stroke
				(width 0.1)
				(type default)
			)
			(layer "F.Fab")
		)
		(fp_line
			(start 0.67945 -0.3048)
			(end 0.67945 0.3048)
			(stroke
				(width 0.1)
				(type default)
			)
			(layer "F.Fab")
		)
		(fp_line
			(start 0.67945 0.3048)
			(end 0.120396 0.3048)
			(stroke
				(width 0.1)
				(type default)
			)
			(layer "F.Fab")
		)
		(pad "1" smd circle
			(at -0.40005 0)
			(size 0 0)
			(layers "F.Cu" "F.Mask" "F.Paste")
			(net "GND")
		)
		(pad "2" smd circle
			(at 0.40005 0)
			(size 0 0)
			(layers "F.Cu" "F.Mask" "F.Paste")
			(net "PVCCINFAON_CPU1_VREF")
		)
	)
	(footprint ""
		(layer "F.Cu")
		(at 184.658 -93.91015 90)
		(property "Reference" "R4760"
			(at 0 0 90)
			(layer "F.SilkS")
			(hide yes)
			(effects
				(font
					(size 1.27 1.27)
				)
			)
		)
		(property "Value" ""
			(at 0 0 90)
			(layer "F.Fab")
			(effects
				(font
					(size 1.27 1.27)
				)
			)
		)
		(duplicate_pad_numbers_are_jumpers no)
		(fp_line
			(start 0.7874 -0.4064)
			(end 0.7874 0.4064)
			(stroke
				(width 0.1524)
				(type default)
			)
			(layer "F.SilkS")
		)
		(fp_line
			(start -0.7874 -0.4064)
			(end 0.7874 -0.4064)
			(stroke
				(width 0.1524)
				(type default)
			)
			(layer "F.SilkS")
		)
		(fp_line
			(start 0.7874 0.4064)
			(end -0.7874 0.4064)
			(stroke
				(width 0.1524)
				(type default)
			)
			(layer "F.SilkS")
		)
		(fp_line
			(start -0.7874 0.4064)
			(end -0.7874 -0.4064)
			(stroke
				(width 0.1524)
				(type default)
			)
			(layer "F.SilkS")
		)
		(fp_line
			(start -0.12065 -0.305054)
			(end -0.12065 -0.2794)
			(stroke
				(width 0.1)
				(type default)
			)
			(layer "F.Fab")
		)
		(fp_line
			(start -0.67945 -0.305054)
			(end -0.12065 -0.305054)
			(stroke
				(width 0.1)
				(type default)
			)
			(layer "F.Fab")
		)
		(fp_line
			(start 0.67945 -0.3048)
			(end 0.67945 0.3048)
			(stroke
				(width 0.1)
				(type default)
			)
			(layer "F.Fab")
		)
		(fp_line
			(start 0.12065 -0.3048)
			(end 0.67945 -0.3048)
			(stroke
				(width 0.1)
				(type default)
			)
			(layer "F.Fab")
		)
		(fp_line
			(start 0.12065 -0.2794)
			(end 0.12065 -0.3048)
			(stroke
				(width 0.1)
				(type default)
			)
			(layer "F.Fab")
		)
		(fp_line
			(start -0.12065 -0.2794)
			(end 0.12065 -0.2794)
			(stroke
				(width 0.1)
				(type default)
			)
			(layer "F.Fab")
		)
		(fp_line
			(start 0.120396 0.2794)
			(end -0.12065 0.2794)
			(stroke
				(width 0.1)
				(type default)
			)
			(layer "F.Fab")
		)
		(fp_line
			(start -0.12065 0.2794)
			(end -0.12065 0.3048)
			(stroke
				(width 0.1)
				(type default)
			)
			(layer "F.Fab")
		)
		(fp_line
			(start 0.67945 0.3048)
			(end 0.120396 0.3048)
			(stroke
				(width 0.1)
				(type default)
			)
			(layer "F.Fab")
		)
		(fp_line
			(start 0.120396 0.3048)
			(end 0.120396 0.2794)
			(stroke
				(width 0.1)
				(type default)
			)
			(layer "F.Fab")
		)
		(fp_line
			(start -0.12065 0.3048)
			(end -0.67945 0.3048)
			(stroke
				(width 0.1)
				(type default)
			)
			(layer "F.Fab")
		)
		(fp_line
			(start -0.67945 0.3048)
			(end -0.67945 -0.305054)
			(stroke
				(width 0.1)
				(type default)
			)
			(layer "F.Fab")
		)
		(pad "1" smd circle
			(at -0.40005 0 90)
			(size 0 0)
			(layers "F.Cu" "F.Mask" "F.Paste")
			(net "HP_LVC3_OCP_V3_2_PWRGD_R")
		)
		(pad "2" smd circle
			(at 0.40005 0 90)
			(size 0 0)
			(layers "F.Cu" "F.Mask" "F.Paste")
			(net "HP_LVC3_OCP_V3_2_FUSE_PWRGD")
		)
	)
)
